(kicad_pcb
	(version 20260206)
	(generator "pcbnew")
	(generator_version "10.0")
	(general
		(thickness 1.6)
		(legacy_teardrops no)
	)
	(paper "A4")
	(title_block
		(title "03242023_DA0F0TMBIJ0_F0T_Motherboard_J_brd_V01_OCP.brd")
		(comment 1 "Grand Teton / footprint 3586 of 6105 (J23), pads 225-291 of 291")
	)
	(layers
		(0 "F.Cu" signal "TOP")
		(4 "In1.Cu" signal "GND")
		(6 "In2.Cu" signal "IN1")
		(8 "In3.Cu" signal "GND1")
		(10 "In4.Cu" signal "IN2")
		(12 "In5.Cu" signal "GND2")
		(14 "In6.Cu" signal "IN3")
		(16 "In7.Cu" signal "GND3")
		(18 "In8.Cu" signal "VCC")
		(20 "In9.Cu" signal "VCC1")
		(22 "In10.Cu" signal "GND4")
		(24 "In11.Cu" signal "IN4")
		(26 "In12.Cu" signal "GND5")
		(28 "In13.Cu" signal "IN5")
		(30 "In14.Cu" signal "GND6")
		(32 "In15.Cu" signal "IN6")
		(34 "In16.Cu" signal "GND7")
		(2 "B.Cu" signal "BOTTOM")
		(9 "F.Adhes" user "F.Adhesive")
		(11 "B.Adhes" user "B.Adhesive")
		(13 "F.Paste" user "Package Geometry/Pastemask Top")
		(15 "B.Paste" user "Package Geometry/Pastemask Bottom")
		(5 "F.SilkS" user "Ref Des/Silkscreen Top")
		(7 "B.SilkS" user "Ref Des/Silkscreen Bottom")
		(1 "F.Mask" user "Board Geometry/Soldermask Top")
		(3 "B.Mask" user "Board Geometry/Soldermask Bottom")
		(17 "Dwgs.User" user "User.Drawings")
		(19 "Cmts.User" user "User.Comments")
		(21 "Eco1.User" user "User.Eco1")
		(23 "Eco2.User" user "User.Eco2")
		(25 "Edge.Cuts" user "Board Geometry/Outline")
		(27 "Margin" user)
		(31 "F.CrtYd" user "Package Geometry/Place Bound Top")
		(29 "B.CrtYd" user "Package Geometry/Place Bound Bottom")
		(35 "F.Fab" user "Ref Des/Assembly Top")
		(33 "B.Fab" user "Ref Des/Assembly Bottom")
	)
	(footprint ""
		(layer "F.Cu")
		(at 10.19048 -258.091686)
		(property "Reference" "J23"
			(at -5.69468 -80.480408 0)
			(unlocked yes)
			(layer "F.SilkS")
			(effects
				(font
					(size 0.7874 0.5842)
					(thickness 0.1524)
				)
				(justify left)
			)
		)
		(property "Value" ""
			(at 0 0 0)
			(layer "F.Fab")
			(effects
				(font
					(size 1.27 1.27)
				)
			)
		)
		(duplicate_pad_numbers_are_jumpers no)
		(pad "225" smd rect
			(at 2.050034 9.774936 270)
			(size 0.519938 1.4986)
			(layers "F.Cu" "F.Mask" "F.Paste")
			(net "M_D_CPU1_SB_CA<5>")
		)
		(pad "226" smd rect
			(at 2.050034 10.625074 270)
			(size 0.519938 1.4986)
			(layers "F.Cu" "F.Mask" "F.Paste")
			(net "GND")
		)
		(pad "227" smd rect
			(at 2.050034 11.474958 270)
			(size 0.519938 1.4986)
			(layers "F.Cu" "F.Mask" "F.Paste")
			(net "M_D_CPU1_SB_PAR")
		)
		(pad "228" smd rect
			(at 2.050034 12.325096 270)
			(size 0.519938 1.4986)
			(layers "F.Cu" "F.Mask" "F.Paste")
			(net "GND")
		)
		(pad "229" smd rect
			(at 2.050034 13.17498 270)
			(size 0.519938 1.4986)
			(layers "F.Cu" "F.Mask" "F.Paste")
			(net "M_D_CPU1_SB_CS_N<1>")
		)
		(pad "230" smd rect
			(at 2.050034 14.025118 270)
			(size 0.519938 1.4986)
			(layers "F.Cu" "F.Mask" "F.Paste")
			(net "GND")
		)
		(pad "231" smd rect
			(at 2.050034 14.875002 270)
			(size 0.519938 1.4986)
			(layers "F.Cu" "F.Mask" "F.Paste")
			(net "TP_CHD_CPU1_DIMM1_FRU_5")
		)
		(pad "232" smd rect
			(at 2.050034 15.724886 270)
			(size 0.519938 1.4986)
			(layers "F.Cu" "F.Mask" "F.Paste")
			(net "TP_CHD_CPU1_DIMM1_FRU_6")
		)
		(pad "233" smd rect
			(at 2.050034 16.575024 270)
			(size 0.519938 1.4986)
			(layers "F.Cu" "F.Mask" "F.Paste")
			(net "GND")
		)
		(pad "234" smd rect
			(at 2.050034 17.424908 270)
			(size 0.519938 1.4986)
			(layers "F.Cu" "F.Mask" "F.Paste")
			(net "M_D_CPU1_SB_CB<6>")
		)
		(pad "235" smd rect
			(at 2.050034 18.275046 270)
			(size 0.519938 1.4986)
			(layers "F.Cu" "F.Mask" "F.Paste")
			(net "GND")
		)
		(pad "236" smd rect
			(at 2.050034 19.12493 270)
			(size 0.519938 1.4986)
			(layers "F.Cu" "F.Mask" "F.Paste")
			(net "M_D_CPU1_SB_CB<7>")
		)
		(pad "237" smd rect
			(at 2.050034 19.975068 270)
			(size 0.519938 1.4986)
			(layers "F.Cu" "F.Mask" "F.Paste")
			(net "GND")
		)
		(pad "238" smd rect
			(at 2.050034 20.824952 270)
			(size 0.519938 1.4986)
			(layers "F.Cu" "F.Mask" "F.Paste")
			(net "M_D_CPU1_SB_DQS_DN<4>")
		)
		(pad "239" smd rect
			(at 2.050034 21.67509 270)
			(size 0.519938 1.4986)
			(layers "F.Cu" "F.Mask" "F.Paste")
			(net "M_D_CPU1_SB_DQS_DP<4>")
		)
		(pad "240" smd rect
			(at 2.050034 22.524974 270)
			(size 0.519938 1.4986)
			(layers "F.Cu" "F.Mask" "F.Paste")
			(net "GND")
		)
		(pad "241" smd rect
			(at 2.050034 23.375112 270)
			(size 0.519938 1.4986)
			(layers "F.Cu" "F.Mask" "F.Paste")
			(net "M_D_CPU1_SB_CB<2>")
		)
		(pad "242" smd rect
			(at 2.050034 24.224996 270)
			(size 0.519938 1.4986)
			(layers "F.Cu" "F.Mask" "F.Paste")
			(net "GND")
		)
		(pad "243" smd rect
			(at 2.050034 25.07488 270)
			(size 0.519938 1.4986)
			(layers "F.Cu" "F.Mask" "F.Paste")
			(net "M_D_CPU1_SB_CB<3>")
		)
		(pad "244" smd rect
			(at 2.050034 25.925018 270)
			(size 0.519938 1.4986)
			(layers "F.Cu" "F.Mask" "F.Paste")
			(net "GND")
		)
		(pad "245" smd rect
			(at 2.050034 26.774902 270)
			(size 0.519938 1.4986)
			(layers "F.Cu" "F.Mask" "F.Paste")
			(net "M_D_CPU1_SB_DQ<2>")
		)
		(pad "246" smd rect
			(at 2.050034 27.62504 270)
			(size 0.519938 1.4986)
			(layers "F.Cu" "F.Mask" "F.Paste")
			(net "GND")
		)
		(pad "247" smd rect
			(at 2.050034 28.474924 270)
			(size 0.519938 1.4986)
			(layers "F.Cu" "F.Mask" "F.Paste")
			(net "M_D_CPU1_SB_DQ<3>")
		)
		(pad "248" smd rect
			(at 2.050034 29.325062 270)
			(size 0.519938 1.4986)
			(layers "F.Cu" "F.Mask" "F.Paste")
			(net "GND")
		)
		(pad "249" smd rect
			(at 2.050034 30.174946 270)
			(size 0.519938 1.4986)
			(layers "F.Cu" "F.Mask" "F.Paste")
			(net "M_D_CPU1_SB_DQS_DN<5>")
		)
		(pad "250" smd rect
			(at 2.050034 31.025084 270)
			(size 0.519938 1.4986)
			(layers "F.Cu" "F.Mask" "F.Paste")
			(net "M_D_CPU1_SB_DQS_DP<5>")
		)
		(pad "251" smd rect
			(at 2.050034 31.874968 270)
			(size 0.519938 1.4986)
			(layers "F.Cu" "F.Mask" "F.Paste")
			(net "GND")
		)
		(pad "252" smd rect
			(at 2.050034 32.725106 270)
			(size 0.519938 1.4986)
			(layers "F.Cu" "F.Mask" "F.Paste")
			(net "M_D_CPU1_SB_DQ<6>")
		)
		(pad "253" smd rect
			(at 2.050034 33.57499 270)
			(size 0.519938 1.4986)
			(layers "F.Cu" "F.Mask" "F.Paste")
			(net "GND")
		)
		(pad "254" smd rect
			(at 2.050034 34.425128 270)
			(size 0.519938 1.4986)
			(layers "F.Cu" "F.Mask" "F.Paste")
			(net "M_D_CPU1_SB_DQ<7>")
		)
		(pad "255" smd rect
			(at 2.050034 35.275012 270)
			(size 0.519938 1.4986)
			(layers "F.Cu" "F.Mask" "F.Paste")
			(net "GND")
		)
		(pad "256" smd rect
			(at 2.050034 36.124896 270)
			(size 0.519938 1.4986)
			(layers "F.Cu" "F.Mask" "F.Paste")
			(net "M_D_CPU1_SB_DQ<10>")
		)
		(pad "257" smd rect
			(at 2.050034 36.975034 270)
			(size 0.519938 1.4986)
			(layers "F.Cu" "F.Mask" "F.Paste")
			(net "GND")
		)
		(pad "258" smd rect
			(at 2.050034 37.824918 270)
			(size 0.519938 1.4986)
			(layers "F.Cu" "F.Mask" "F.Paste")
			(net "M_D_CPU1_SB_DQ<11>")
		)
		(pad "259" smd rect
			(at 2.050034 38.675056 270)
			(size 0.519938 1.4986)
			(layers "F.Cu" "F.Mask" "F.Paste")
			(net "GND")
		)
		(pad "260" smd rect
			(at 2.050034 39.52494 270)
			(size 0.519938 1.4986)
			(layers "F.Cu" "F.Mask" "F.Paste")
			(net "M_D_CPU1_SB_DQS_DN<6>")
		)
		(pad "261" smd rect
			(at 2.050034 40.375078 270)
			(size 0.519938 1.4986)
			(layers "F.Cu" "F.Mask" "F.Paste")
			(net "M_D_CPU1_SB_DQS_DP<6>")
		)
		(pad "262" smd rect
			(at 2.050034 41.224962 270)
			(size 0.519938 1.4986)
			(layers "F.Cu" "F.Mask" "F.Paste")
			(net "GND")
		)
		(pad "263" smd rect
			(at 2.050034 42.0751 270)
			(size 0.519938 1.4986)
			(layers "F.Cu" "F.Mask" "F.Paste")
			(net "M_D_CPU1_SB_DQ<14>")
		)
		(pad "264" smd rect
			(at 2.050034 42.924984 270)
			(size 0.519938 1.4986)
			(layers "F.Cu" "F.Mask" "F.Paste")
			(net "GND")
		)
		(pad "265" smd rect
			(at 2.050034 43.775122 270)
			(size 0.519938 1.4986)
			(layers "F.Cu" "F.Mask" "F.Paste")
			(net "M_D_CPU1_SB_DQ<15>")
		)
		(pad "266" smd rect
			(at 2.050034 44.625006 270)
			(size 0.519938 1.4986)
			(layers "F.Cu" "F.Mask" "F.Paste")
			(net "GND")
		)
		(pad "267" smd rect
			(at 2.050034 45.47489 270)
			(size 0.519938 1.4986)
			(layers "F.Cu" "F.Mask" "F.Paste")
			(net "M_D_CPU1_SB_DQ<18>")
		)
		(pad "268" smd rect
			(at 2.050034 46.325028 270)
			(size 0.519938 1.4986)
			(layers "F.Cu" "F.Mask" "F.Paste")
			(net "GND")
		)
		(pad "269" smd rect
			(at 2.050034 47.174912 270)
			(size 0.519938 1.4986)
			(layers "F.Cu" "F.Mask" "F.Paste")
			(net "M_D_CPU1_SB_DQ<19>")
		)
		(pad "270" smd rect
			(at 2.050034 48.02505 270)
			(size 0.519938 1.4986)
			(layers "F.Cu" "F.Mask" "F.Paste")
			(net "GND")
		)
		(pad "271" smd rect
			(at 2.050034 48.874934 270)
			(size 0.519938 1.4986)
			(layers "F.Cu" "F.Mask" "F.Paste")
			(net "M_D_CPU1_SB_DQS_DN<7>")
		)
		(pad "272" smd rect
			(at 2.050034 49.725072 270)
			(size 0.519938 1.4986)
			(layers "F.Cu" "F.Mask" "F.Paste")
			(net "M_D_CPU1_SB_DQS_DP<7>")
		)
		(pad "273" smd rect
			(at 2.050034 50.574956 270)
			(size 0.519938 1.4986)
			(layers "F.Cu" "F.Mask" "F.Paste")
			(net "GND")
		)
		(pad "274" smd rect
			(at 2.050034 51.425094 270)
			(size 0.519938 1.4986)
			(layers "F.Cu" "F.Mask" "F.Paste")
			(net "M_D_CPU1_SB_DQ<22>")
		)
		(pad "275" smd rect
			(at 2.050034 52.274978 270)
			(size 0.519938 1.4986)
			(layers "F.Cu" "F.Mask" "F.Paste")
			(net "GND")
		)
		(pad "276" smd rect
			(at 2.050034 53.125116 270)
			(size 0.519938 1.4986)
			(layers "F.Cu" "F.Mask" "F.Paste")
			(net "M_D_CPU1_SB_DQ<23>")
		)
		(pad "277" smd rect
			(at 2.050034 53.975 270)
			(size 0.519938 1.4986)
			(layers "F.Cu" "F.Mask" "F.Paste")
			(net "GND")
		)
		(pad "278" smd rect
			(at 2.050034 54.824884 270)
			(size 0.519938 1.4986)
			(layers "F.Cu" "F.Mask" "F.Paste")
			(net "M_D_CPU1_SB_DQ<26>")
		)
		(pad "279" smd rect
			(at 2.050034 55.675022 270)
			(size 0.519938 1.4986)
			(layers "F.Cu" "F.Mask" "F.Paste")
			(net "GND")
		)
		(pad "280" smd rect
			(at 2.050034 56.524906 270)
			(size 0.519938 1.4986)
			(layers "F.Cu" "F.Mask" "F.Paste")
			(net "M_D_CPU1_SB_DQ<27>")
		)
		(pad "281" smd rect
			(at 2.050034 57.375044 270)
			(size 0.519938 1.4986)
			(layers "F.Cu" "F.Mask" "F.Paste")
			(net "GND")
		)
		(pad "282" smd rect
			(at 2.050034 58.224928 270)
			(size 0.519938 1.4986)
			(layers "F.Cu" "F.Mask" "F.Paste")
			(net "M_D_CPU1_SB_DQS_DN<8>")
		)
		(pad "283" smd rect
			(at 2.050034 59.075066 270)
			(size 0.519938 1.4986)
			(layers "F.Cu" "F.Mask" "F.Paste")
			(net "M_D_CPU1_SB_DQS_DP<8>")
		)
		(pad "284" smd rect
			(at 2.050034 59.92495 270)
			(size 0.519938 1.4986)
			(layers "F.Cu" "F.Mask" "F.Paste")
			(net "GND")
		)
		(pad "285" smd rect
			(at 2.050034 60.775088 270)
			(size 0.519938 1.4986)
			(layers "F.Cu" "F.Mask" "F.Paste")
			(net "M_D_CPU1_SB_DQ<30>")
		)
		(pad "286" smd rect
			(at 2.050034 61.624972 270)
			(size 0.519938 1.4986)
			(layers "F.Cu" "F.Mask" "F.Paste")
			(net "GND")
		)
		(pad "287" smd rect
			(at 2.050034 62.47511 270)
			(size 0.519938 1.4986)
			(layers "F.Cu" "F.Mask" "F.Paste")
			(net "M_D_CPU1_SB_DQ<31>")
		)
		(pad "288" smd rect
			(at 2.050034 63.324994 270)
			(size 0.519938 1.4986)
			(layers "F.Cu" "F.Mask" "F.Paste")
			(net "GND")
		)
		(pad "G1" thru_hole oval
			(at 0 -68.97497)
			(size 2.8194 1.5748)
			(drill oval 2.4384 1.1938)
			(layers "*.Cu" "*.Mask")
			(remove_unused_layers no)
			(net "GND")
			(clearance 0.127)
			(thermal_gap 0.127)
		)
		(pad "G2" thru_hole oval
			(at 0 3.875024)
			(size 2.8194 1.5748)
			(drill oval 2.4384 1.1938)
			(layers "*.Cu" "*.Mask")
			(remove_unused_layers no)
			(net "GND")
			(clearance 0.127)
			(thermal_gap 0.127)
		)
		(pad "G3" thru_hole oval
			(at 0 68.97497)
			(size 2.8194 1.5748)
			(drill oval 2.4384 1.1938)
			(layers "*.Cu" "*.Mask")
			(remove_unused_layers no)
			(net "GND")
			(clearance 0.127)
			(thermal_gap 0.127)
		)
	)
)
